(kicad_pcb
	(version 20260206)
	(generator "pcbnew")
	(generator_version "10.0")
	(general
		(thickness 1.6)
		(legacy_teardrops no)
	)
	(paper "A4")
	(title_block
		(title "12092022_DA0F0TFB6D0_F0T_FAN_BOARD_MP5048_D_brd_v02_OCP.brd")
		(comment 1 "Grand Teton / footprints 211-217 of 924")
	)
	(layers
		(0 "F.Cu" signal "TOP")
		(4 "In1.Cu" signal "GND")
		(6 "In2.Cu" signal "IN1")
		(8 "In3.Cu" signal "IN2")
		(10 "In4.Cu" signal "GND1")
		(2 "B.Cu" signal "BOTTOM")
		(9 "F.Adhes" user "F.Adhesive")
		(11 "B.Adhes" user "B.Adhesive")
		(13 "F.Paste" user "Package Geometry/Pastemask Top")
		(15 "B.Paste" user "Package Geometry/Pastemask Bottom")
		(5 "F.SilkS" user "Ref Des/Silkscreen Top")
		(7 "B.SilkS" user "Ref Des/Silkscreen Bottom")
		(1 "F.Mask" user "Board Geometry/Soldermask Top")
		(3 "B.Mask" user "Board Geometry/Soldermask Bottom")
		(17 "Dwgs.User" user "User.Drawings")
		(19 "Cmts.User" user "User.Comments")
		(21 "Eco1.User" user "User.Eco1")
		(23 "Eco2.User" user "User.Eco2")
		(25 "Edge.Cuts" user "Board Geometry/Outline")
		(27 "Margin" user)
		(31 "F.CrtYd" user "Package Geometry/Place Bound Top")
		(29 "B.CrtYd" user "Package Geometry/Place Bound Bottom")
		(35 "F.Fab" user "Ref Des/Assembly Top")
		(33 "B.Fab" user "Ref Des/Assembly Bottom")
	)
	(footprint ""
		(layer "F.Cu")
		(at 26.289 -116.84 180)
		(property "Reference" "U65"
			(at 1.4732 -2.05867 0)
			(unlocked yes)
			(layer "F.SilkS")
			(effects
				(font
					(size 0.7874 0.5842)
					(thickness 0.1524)
				)
				(justify left)
			)
		)
		(property "Value" ""
			(at 0 0 180)
			(layer "F.Fab")
			(effects
				(font
					(size 1.27 1.27)
				)
			)
		)
		(duplicate_pad_numbers_are_jumpers no)
		(fp_line
			(start 1.538478 1.150874)
			(end 1.538478 -1.150874)
			(stroke
				(width 0.1524)
				(type default)
			)
			(layer "F.SilkS")
		)
		(fp_line
			(start 1.538478 -1.150874)
			(end -1.538478 -1.150874)
			(stroke
				(width 0.1524)
				(type default)
			)
			(layer "F.SilkS")
		)
		(fp_line
			(start -1.538478 1.150874)
			(end 1.538478 1.150874)
			(stroke
				(width 0.1524)
				(type default)
			)
			(layer "F.SilkS")
		)
		(fp_line
			(start -1.538478 -1.150874)
			(end -1.538478 1.150874)
			(stroke
				(width 0.1524)
				(type default)
			)
			(layer "F.SilkS")
		)
		(fp_line
			(start 0.674878 1.100074)
			(end 0.674878 -1.100074)
			(stroke
				(width 0.1)
				(type default)
			)
			(layer "F.Fab")
		)
		(fp_line
			(start 0.674878 -1.100074)
			(end -0.674878 -1.100074)
			(stroke
				(width 0.1)
				(type default)
			)
			(layer "F.Fab")
		)
		(fp_line
			(start -0.674878 1.100074)
			(end 0.674878 1.100074)
			(stroke
				(width 0.1)
				(type default)
			)
			(layer "F.Fab")
		)
		(fp_line
			(start -0.674878 -1.100074)
			(end -0.674878 1.100074)
			(stroke
				(width 0.1)
				(type default)
			)
			(layer "F.Fab")
		)
		(pad "1" smd rect
			(at -0.94996 -0.649986 270)
			(size 0.7112 0.9144)
			(layers "F.Cu" "F.Mask" "F.Paste")
			(net "FAN_2_PWM_IL")
		)
		(pad "2" smd rect
			(at -0.94996 0.649986 270)
			(size 0.7112 0.9144)
			(layers "F.Cu" "F.Mask" "F.Paste")
			(net "FAN_2_PWM_OL")
		)
		(pad "3" smd rect
			(at 0.94996 0 270)
			(size 0.7112 0.9144)
			(layers "F.Cu" "F.Mask" "F.Paste")
			(net "FAN_2_PWM_BUF")
		)
	)
	(footprint ""
		(layer "F.Cu")
		(at 18.669 -19.098768 180)
		(property "Reference" "D244"
			(at -1.69164 1.600962 0)
			(unlocked yes)
			(layer "F.SilkS")
			(effects
				(font
					(size 0.7874 0.5842)
					(thickness 0.1524)
				)
				(justify left)
			)
		)
		(property "Value" ""
			(at 0 0 180)
			(layer "F.Fab")
			(effects
				(font
					(size 1.27 1.27)
				)
			)
		)
		(duplicate_pad_numbers_are_jumpers no)
		(fp_line
			(start 0.94488 0.450088)
			(end 0.94488 -0.450088)
			(stroke
				(width 0.1524)
				(type default)
			)
			(layer "F.SilkS")
		)
		(fp_line
			(start 0.94488 -0.450088)
			(end -0.854964 -0.450088)
			(stroke
				(width 0.1524)
				(type default)
			)
			(layer "F.SilkS")
		)
		(fp_line
			(start 0.870458 -0.2794)
			(end 0.845058 0.4064)
			(stroke
				(width 0.1524)
				(type default)
			)
			(layer "F.SilkS")
		)
		(fp_line
			(start 0.845058 0.4064)
			(end 0.845058 -0.381)
			(stroke
				(width 0.1524)
				(type default)
			)
			(layer "F.SilkS")
		)
		(fp_line
			(start -0.854964 0.450088)
			(end 0.925068 0.450088)
			(stroke
				(width 0.1524)
				(type default)
			)
			(layer "F.SilkS")
		)
		(fp_line
			(start -0.854964 -0.450088)
			(end -0.854964 0.450088)
			(stroke
				(width 0.1524)
				(type default)
			)
			(layer "F.SilkS")
		)
		(fp_line
			(start 0.54991 0.350012)
			(end 0.54991 -0.350012)
			(stroke
				(width 0.1)
				(type default)
			)
			(layer "F.Fab")
		)
		(fp_line
			(start 0.54991 -0.350012)
			(end -0.54991 -0.350012)
			(stroke
				(width 0.1)
				(type default)
			)
			(layer "F.Fab")
		)
		(fp_line
			(start -0.54991 0.350012)
			(end 0.54991 0.350012)
			(stroke
				(width 0.1)
				(type default)
			)
			(layer "F.Fab")
		)
		(fp_line
			(start -0.54991 -0.350012)
			(end -0.54991 0.350012)
			(stroke
				(width 0.1)
				(type default)
			)
			(layer "F.Fab")
		)
		(fp_text user "-"
			(at 1.778 0.935482 0)
			(unlocked yes)
			(layer "F.SilkS")
			(effects
				(font
					(size 1.905 1.4224)
					(thickness 0.1524)
				)
				(justify left)
			)
		)
		(fp_text user "+"
			(at -0.508 0.935482 0)
			(unlocked yes)
			(layer "F.SilkS")
			(effects
				(font
					(size 1.905 1.4224)
					(thickness 0.1524)
				)
				(justify left)
			)
		)
		(fp_text user "-"
			(at 2.48539 0.239014 0)
			(unlocked yes)
			(layer "F.Fab")
			(effects
				(font
					(size 1.905 1.4224)
					(thickness 0.1524)
				)
				(justify left)
			)
		)
		(fp_text user "+"
			(at -0.808228 0.239014 0)
			(unlocked yes)
			(layer "F.Fab")
			(effects
				(font
					(size 1.905 1.4224)
					(thickness 0.1524)
				)
				(justify left)
			)
		)
		(pad "A" smd rect
			(at -0.424942 0 180)
			(size 0.5588 0.6096)
			(layers "F.Cu" "F.Mask" "F.Paste")
			(net "GND")
		)
		(pad "C" smd rect
			(at 0.424942 0)
			(size 0.5588 0.6096)
			(layers "F.Cu" "F.Mask" "F.Paste")
			(net "FAN_4_PWM_IL_R")
		)
	)
	(footprint ""
		(layer "F.Cu")
		(at 32.766 -287.147 -90)
		(property "Reference" "C2023"
			(at 0 0 270)
			(layer "F.SilkS")
			(hide yes)
			(effects
				(font
					(size 1.27 1.27)
				)
			)
		)
		(property "Value" ""
			(at 0 0 270)
			(layer "F.Fab")
			(effects
				(font
					(size 1.27 1.27)
				)
			)
		)
		(duplicate_pad_numbers_are_jumpers no)
		(fp_line
			(start -0.7874 0.4064)
			(end -0.7874 -0.4064)
			(stroke
				(width 0.1524)
				(type default)
			)
			(layer "F.SilkS")
		)
		(fp_line
			(start 0.7874 0.4064)
			(end -0.7874 0.4064)
			(stroke
				(width 0.1524)
				(type default)
			)
			(layer "F.SilkS")
		)
		(fp_line
			(start -0.7874 -0.4064)
			(end 0.7874 -0.4064)
			(stroke
				(width 0.1524)
				(type default)
			)
			(layer "F.SilkS")
		)
		(fp_line
			(start 0.7874 -0.4064)
			(end 0.7874 0.4064)
			(stroke
				(width 0.1524)
				(type default)
			)
			(layer "F.SilkS")
		)
		(fp_line
			(start -0.67945 0.3048)
			(end -0.67945 -0.305054)
			(stroke
				(width 0.1)
				(type default)
			)
			(layer "F.Fab")
		)
		(fp_line
			(start -0.12065 0.3048)
			(end -0.67945 0.3048)
			(stroke
				(width 0.1)
				(type default)
			)
			(layer "F.Fab")
		)
		(fp_line
			(start 0.120396 0.3048)
			(end 0.120396 0.2794)
			(stroke
				(width 0.1)
				(type default)
			)
			(layer "F.Fab")
		)
		(fp_line
			(start 0.67945 0.3048)
			(end 0.120396 0.3048)
			(stroke
				(width 0.1)
				(type default)
			)
			(layer "F.Fab")
		)
		(fp_line
			(start -0.12065 0.2794)
			(end -0.12065 0.3048)
			(stroke
				(width 0.1)
				(type default)
			)
			(layer "F.Fab")
		)
		(fp_line
			(start 0.120396 0.2794)
			(end -0.12065 0.2794)
			(stroke
				(width 0.1)
				(type default)
			)
			(layer "F.Fab")
		)
		(fp_line
			(start -0.12065 -0.2794)
			(end 0.12065 -0.2794)
			(stroke
				(width 0.1)
				(type default)
			)
			(layer "F.Fab")
		)
		(fp_line
			(start 0.12065 -0.2794)
			(end 0.12065 -0.3048)
			(stroke
				(width 0.1)
				(type default)
			)
			(layer "F.Fab")
		)
		(fp_line
			(start 0.12065 -0.3048)
			(end 0.67945 -0.3048)
			(stroke
				(width 0.1)
				(type default)
			)
			(layer "F.Fab")
		)
		(fp_line
			(start 0.67945 -0.3048)
			(end 0.67945 0.3048)
			(stroke
				(width 0.1)
				(type default)
			)
			(layer "F.Fab")
		)
		(fp_line
			(start -0.67945 -0.305054)
			(end -0.12065 -0.305054)
			(stroke
				(width 0.1)
				(type default)
			)
			(layer "F.Fab")
		)
		(fp_line
			(start -0.12065 -0.305054)
			(end -0.12065 -0.2794)
			(stroke
				(width 0.1)
				(type default)
			)
			(layer "F.Fab")
		)
		(pad "1" smd circle
			(at -0.40005 0 270)
			(size 0 0)
			(layers "F.Cu" "F.Mask" "F.Paste")
			(net "FAN_0_TACH_OL_R")
		)
		(pad "2" smd circle
			(at 0.40005 0 270)
			(size 0 0)
			(layers "F.Cu" "F.Mask" "F.Paste")
			(net "GND")
		)
	)
	(footprint ""
		(layer "F.Cu")
		(at 14.351 -205.74 180)
		(property "Reference" "D251"
			(at 4.064 0.48133 0)
			(unlocked yes)
			(layer "F.SilkS")
			(effects
				(font
					(size 0.7874 0.5842)
					(thickness 0.1524)
				)
				(justify left)
			)
		)
		(property "Value" ""
			(at 0 0 180)
			(layer "F.Fab")
			(effects
				(font
					(size 1.27 1.27)
				)
			)
		)
		(duplicate_pad_numbers_are_jumpers no)
		(fp_line
			(start 0.94488 0.450088)
			(end 0.94488 -0.450088)
			(stroke
				(width 0.1524)
				(type default)
			)
			(layer "F.SilkS")
		)
		(fp_line
			(start 0.94488 -0.450088)
			(end -0.854964 -0.450088)
			(stroke
				(width 0.1524)
				(type default)
			)
			(layer "F.SilkS")
		)
		(fp_line
			(start 0.870458 -0.2794)
			(end 0.845058 0.4064)
			(stroke
				(width 0.1524)
				(type default)
			)
			(layer "F.SilkS")
		)
		(fp_line
			(start 0.845058 0.4064)
			(end 0.845058 -0.381)
			(stroke
				(width 0.1524)
				(type default)
			)
			(layer "F.SilkS")
		)
		(fp_line
			(start -0.854964 0.450088)
			(end 0.925068 0.450088)
			(stroke
				(width 0.1524)
				(type default)
			)
			(layer "F.SilkS")
		)
		(fp_line
			(start -0.854964 -0.450088)
			(end -0.854964 0.450088)
			(stroke
				(width 0.1524)
				(type default)
			)
			(layer "F.SilkS")
		)
		(fp_line
			(start 0.54991 0.350012)
			(end 0.54991 -0.350012)
			(stroke
				(width 0.1)
				(type default)
			)
			(layer "F.Fab")
		)
		(fp_line
			(start 0.54991 -0.350012)
			(end -0.54991 -0.350012)
			(stroke
				(width 0.1)
				(type default)
			)
			(layer "F.Fab")
		)
		(fp_line
			(start -0.54991 0.350012)
			(end 0.54991 0.350012)
			(stroke
				(width 0.1)
				(type default)
			)
			(layer "F.Fab")
		)
		(fp_line
			(start -0.54991 -0.350012)
			(end -0.54991 0.350012)
			(stroke
				(width 0.1)
				(type default)
			)
			(layer "F.Fab")
		)
		(fp_text user "-"
			(at 2.286 -0.15875 0)
			(unlocked yes)
			(layer "F.SilkS")
			(effects
				(font
					(size 1.905 1.4224)
					(thickness 0.1524)
				)
				(justify left)
			)
		)
		(fp_text user "+"
			(at -0.635 -0.15875 0)
			(unlocked yes)
			(layer "F.SilkS")
			(effects
				(font
					(size 1.905 1.4224)
					(thickness 0.1524)
				)
				(justify left)
			)
		)
		(fp_text user "-"
			(at 2.48539 0.239014 0)
			(unlocked yes)
			(layer "F.Fab")
			(effects
				(font
					(size 1.905 1.4224)
					(thickness 0.1524)
				)
				(justify left)
			)
		)
		(fp_text user "+"
			(at -0.808228 0.239014 0)
			(unlocked yes)
			(layer "F.Fab")
			(effects
				(font
					(size 1.905 1.4224)
					(thickness 0.1524)
				)
				(justify left)
			)
		)
		(pad "A" smd rect
			(at -0.424942 0 180)
			(size 0.5588 0.6096)
			(layers "F.Cu" "F.Mask" "F.Paste")
			(net "GND")
		)
		(pad "C" smd rect
			(at 0.424942 0)
			(size 0.5588 0.6096)
			(layers "F.Cu" "F.Mask" "F.Paste")
			(net "FAN_6_FAIL_R_LED_N")
		)
	)
	(footprint ""
		(layer "F.Cu")
		(at 23.241 -13.8938 -90)
		(property "Reference" "R4989"
			(at 0 0 270)
			(layer "F.SilkS")
			(hide yes)
			(effects
				(font
					(size 1.27 1.27)
				)
			)
		)
		(property "Value" ""
			(at 0 0 270)
			(layer "F.Fab")
			(effects
				(font
					(size 1.27 1.27)
				)
			)
		)
		(duplicate_pad_numbers_are_jumpers no)
		(fp_line
			(start -0.7874 0.4064)
			(end -0.7874 -0.4064)
			(stroke
				(width 0.1524)
				(type default)
			)
			(layer "F.SilkS")
		)
		(fp_line
			(start 0.7874 0.4064)
			(end -0.7874 0.4064)
			(stroke
				(width 0.1524)
				(type default)
			)
			(layer "F.SilkS")
		)
		(fp_line
			(start -0.7874 -0.4064)
			(end 0.7874 -0.4064)
			(stroke
				(width 0.1524)
				(type default)
			)
			(layer "F.SilkS")
		)
		(fp_line
			(start 0.7874 -0.4064)
			(end 0.7874 0.4064)
			(stroke
				(width 0.1524)
				(type default)
			)
			(layer "F.SilkS")
		)
		(fp_line
			(start -0.67945 0.3048)
			(end -0.67945 -0.305054)
			(stroke
				(width 0.1)
				(type default)
			)
			(layer "F.Fab")
		)
		(fp_line
			(start -0.12065 0.3048)
			(end -0.67945 0.3048)
			(stroke
				(width 0.1)
				(type default)
			)
			(layer "F.Fab")
		)
		(fp_line
			(start 0.120396 0.3048)
			(end 0.120396 0.2794)
			(stroke
				(width 0.1)
				(type default)
			)
			(layer "F.Fab")
		)
		(fp_line
			(start 0.67945 0.3048)
			(end 0.120396 0.3048)
			(stroke
				(width 0.1)
				(type default)
			)
			(layer "F.Fab")
		)
		(fp_line
			(start -0.12065 0.2794)
			(end -0.12065 0.3048)
			(stroke
				(width 0.1)
				(type default)
			)
			(layer "F.Fab")
		)
		(fp_line
			(start 0.120396 0.2794)
			(end -0.12065 0.2794)
			(stroke
				(width 0.1)
				(type default)
			)
			(layer "F.Fab")
		)
		(fp_line
			(start -0.12065 -0.2794)
			(end 0.12065 -0.2794)
			(stroke
				(width 0.1)
				(type default)
			)
			(layer "F.Fab")
		)
		(fp_line
			(start 0.12065 -0.2794)
			(end 0.12065 -0.3048)
			(stroke
				(width 0.1)
				(type default)
			)
			(layer "F.Fab")
		)
		(fp_line
			(start 0.12065 -0.3048)
			(end 0.67945 -0.3048)
			(stroke
				(width 0.1)
				(type default)
			)
			(layer "F.Fab")
		)
		(fp_line
			(start 0.67945 -0.3048)
			(end 0.67945 0.3048)
			(stroke
				(width 0.1)
				(type default)
			)
			(layer "F.Fab")
		)
		(fp_line
			(start -0.67945 -0.305054)
			(end -0.12065 -0.305054)
			(stroke
				(width 0.1)
				(type default)
			)
			(layer "F.Fab")
		)
		(fp_line
			(start -0.12065 -0.305054)
			(end -0.12065 -0.2794)
			(stroke
				(width 0.1)
				(type default)
			)
			(layer "F.Fab")
		)
		(pad "1" smd circle
			(at -0.40005 0 270)
			(size 0 0)
			(layers "F.Cu" "F.Mask" "F.Paste")
			(net "P3V3_AUX")
		)
		(pad "2" smd circle
			(at 0.40005 0 270)
			(size 0 0)
			(layers "F.Cu" "F.Mask" "F.Paste")
			(net "SMB_PDBV_FAN_R_SCL")
		)
	)
	(footprint ""
		(layer "F.Cu")
		(at 14.361922 -199.076056)
		(property "Reference" "R5221"
			(at 0 0 0)
			(layer "F.SilkS")
			(hide yes)
			(effects
				(font
					(size 1.27 1.27)
				)
			)
		)
		(property "Value" ""
			(at 0 0 0)
			(layer "F.Fab")
			(effects
				(font
					(size 1.27 1.27)
				)
			)
		)
		(duplicate_pad_numbers_are_jumpers no)
		(fp_line
			(start -0.7874 -0.4064)
			(end 0.7874 -0.4064)
			(stroke
				(width 0.1524)
				(type default)
			)
			(layer "F.SilkS")
		)
		(fp_line
			(start -0.7874 0.4064)
			(end -0.7874 -0.4064)
			(stroke
				(width 0.1524)
				(type default)
			)
			(layer "F.SilkS")
		)
		(fp_line
			(start 0.7874 -0.4064)
			(end 0.7874 0.4064)
			(stroke
				(width 0.1524)
				(type default)
			)
			(layer "F.SilkS")
		)
		(fp_line
			(start 0.7874 0.4064)
			(end -0.7874 0.4064)
			(stroke
				(width 0.1524)
				(type default)
			)
			(layer "F.SilkS")
		)
		(fp_line
			(start -0.67945 -0.305054)
			(end -0.12065 -0.305054)
			(stroke
				(width 0.1)
				(type default)
			)
			(layer "F.Fab")
		)
		(fp_line
			(start -0.67945 0.3048)
			(end -0.67945 -0.305054)
			(stroke
				(width 0.1)
				(type default)
			)
			(layer "F.Fab")
		)
		(fp_line
			(start -0.12065 -0.305054)
			(end -0.12065 -0.2794)
			(stroke
				(width 0.1)
				(type default)
			)
			(layer "F.Fab")
		)
		(fp_line
			(start -0.12065 -0.2794)
			(end 0.12065 -0.2794)
			(stroke
				(width 0.1)
				(type default)
			)
			(layer "F.Fab")
		)
		(fp_line
			(start -0.12065 0.2794)
			(end -0.12065 0.3048)
			(stroke
				(width 0.1)
				(type default)
			)
			(layer "F.Fab")
		)
		(fp_line
			(start -0.12065 0.3048)
			(end -0.67945 0.3048)
			(stroke
				(width 0.1)
				(type default)
			)
			(layer "F.Fab")
		)
		(fp_line
			(start 0.120396 0.2794)
			(end -0.12065 0.2794)
			(stroke
				(width 0.1)
				(type default)
			)
			(layer "F.Fab")
		)
		(fp_line
			(start 0.120396 0.3048)
			(end 0.120396 0.2794)
			(stroke
				(width 0.1)
				(type default)
			)
			(layer "F.Fab")
		)
		(fp_line
			(start 0.12065 -0.3048)
			(end 0.67945 -0.3048)
			(stroke
				(width 0.1)
				(type default)
			)
			(layer "F.Fab")
		)
		(fp_line
			(start 0.12065 -0.2794)
			(end 0.12065 -0.3048)
			(stroke
				(width 0.1)
				(type default)
			)
			(layer "F.Fab")
		)
		(fp_line
			(start 0.67945 -0.3048)
			(end 0.67945 0.3048)
			(stroke
				(width 0.1)
				(type default)
			)
			(layer "F.Fab")
		)
		(fp_line
			(start 0.67945 0.3048)
			(end 0.120396 0.3048)
			(stroke
				(width 0.1)
				(type default)
			)
			(layer "F.Fab")
		)
		(pad "1" smd circle
			(at -0.40005 0)
			(size 0 0)
			(layers "F.Cu" "F.Mask" "F.Paste")
			(net "FAN_6_PWM_IL_R")
		)
		(pad "2" smd circle
			(at 0.40005 0)
			(size 0 0)
			(layers "F.Cu" "F.Mask" "F.Paste")
			(net "FAN_6_PWM_IL")
		)
	)
	(footprint ""
		(layer "F.Cu")
		(at 34.671 -198.8058)
		(property "Reference" "U370"
			(at -4.064 -1.62433 0)
			(unlocked yes)
			(layer "F.SilkS")
			(effects
				(font
					(size 0.7874 0.5842)
					(thickness 0.1524)
				)
				(justify left)
			)
		)
		(property "Value" ""
			(at 0 0 0)
			(layer "F.Fab")
			(effects
				(font
					(size 1.27 1.27)
				)
			)
		)
		(duplicate_pad_numbers_are_jumpers no)
		(fp_line
			(start -1.335278 -1.100074)
			(end -1.335278 1.100074)
			(stroke
				(width 0.1524)
				(type default)
			)
			(layer "F.SilkS")
		)
		(fp_line
			(start -1.335278 1.100074)
			(end 1.335278 1.100074)
			(stroke
				(width 0.1524)
				(type default)
			)
			(layer "F.SilkS")
		)
		(fp_line
			(start 1.335278 -1.100074)
			(end -1.335278 -1.100074)
			(stroke
				(width 0.1524)
				(type default)
			)
			(layer "F.SilkS")
		)
		(fp_line
			(start 1.335278 1.100074)
			(end 1.335278 -1.100074)
			(stroke
				(width 0.1524)
				(type default)
			)
			(layer "F.SilkS")
		)
		(fp_line
			(start -0.674878 -1.100074)
			(end -0.674878 1.100074)
			(stroke
				(width 0.1)
				(type default)
			)
			(layer "F.Fab")
		)
		(fp_line
			(start -0.674878 1.100074)
			(end 0.674878 1.100074)
			(stroke
				(width 0.1)
				(type default)
			)
			(layer "F.Fab")
		)
		(fp_line
			(start 0.674878 -1.100074)
			(end -0.674878 -1.100074)
			(stroke
				(width 0.1)
				(type default)
			)
			(layer "F.Fab")
		)
		(fp_line
			(start 0.674878 1.100074)
			(end 0.674878 -1.100074)
			(stroke
				(width 0.1)
				(type default)
			)
			(layer "F.Fab")
		)
		(pad "D" smd rect
			(at 0.8001 0 270)
			(size 0.6096 0.8128)
			(layers "F.Cu" "F.Mask" "F.Paste")
			(net "FAN_1_OK_LED_R_N")
		)
		(pad "G" smd rect
			(at -0.8001 -0.649986 270)
			(size 0.6096 0.8128)
			(layers "F.Cu" "F.Mask" "F.Paste")
			(net "FAN_1_OK_R_LED")
		)
		(pad "S" smd rect
			(at -0.8001 0.649986 270)
			(size 0.6096 0.8128)
			(layers "F.Cu" "F.Mask" "F.Paste")
			(net "GND")
		)
	)
)
